(kicad_pcb
	(version 20241229)
	(generator "pcbnew")
	(generator_version "9.0")
	(general
		(thickness 1.711)
		(legacy_teardrops no)
	)
	(paper "A4")
	(title_block
		(title "Antmicro Baseboard for Jetson AGX Thor")
		(date "2026-02-18")
		(rev "1.1.0")
		(company "Antmicro Ltd")
		(comment 1 "www.antmicro.com")
		(comment 9 "footprints 576-579 of 1170")
	)
	(layers
		(0 "F.Cu" signal)
		(4 "In1.Cu" signal)
		(6 "In2.Cu" signal)
		(8 "In3.Cu" signal)
		(10 "In4.Cu" jumper)
		(12 "In5.Cu" signal)
		(14 "In6.Cu" signal)
		(16 "In7.Cu" signal)
		(18 "In8.Cu" signal)
		(2 "B.Cu" signal)
		(9 "F.Adhes" user "F.Adhesive")
		(11 "B.Adhes" user "B.Adhesive")
		(13 "F.Paste" user)
		(15 "B.Paste" user)
		(5 "F.SilkS" user "F.Silkscreen")
		(7 "B.SilkS" user "B.Silkscreen")
		(1 "F.Mask" user)
		(3 "B.Mask" user)
		(17 "Dwgs.User" user "User.Drawings")
		(19 "Cmts.User" user "User.Comments")
		(21 "Eco1.User" user "User.Eco1")
		(23 "Eco2.User" user "User.Eco2")
		(25 "Edge.Cuts" user)
		(27 "Margin" user)
		(31 "F.CrtYd" user "F.Courtyard")
		(29 "B.CrtYd" user "B.Courtyard")
		(35 "F.Fab" user)
		(33 "B.Fab" user)
	)
	(footprint "antmicro-footprints:C_0402_1005Metric"
		(layer "F.Cu")
		(at 125.569999 64.88 180)
		(descr "Capacitor SMD 0402")
		(tags "capacitor SMD 0402")
		(property "Reference" "C376"
			(at -0.990001 -0.6 0)
			(layer "F.SilkS")
			(effects
				(font
					(size 0.7 0.7)
					(thickness 0.15)
				)
				(justify right top)
			)
		)
		(property "Value" "C_4u7_25V_0402"
			(at -1.022927 2.155213 0)
			(layer "F.Fab")
			(effects
				(font
					(size 0.7 0.7)
					(thickness 0.15)
				)
				(justify right top)
			)
		)
		(property "Datasheet" "https://www.murata.com/products/productdetail?partno=GRM155C61E475ME15%23"
			(at 0 0 0)
			(layer "F.Fab")
			(hide yes)
			(effects
				(font
					(size 1.27 1.27)
					(thickness 0.15)
				)
			)
		)
		(property "Description" "SMD Multilayer Ceramic Capacitor"
			(at 0 0 0)
			(layer "F.Fab")
			(hide yes)
			(effects
				(font
					(size 1.27 1.27)
					(thickness 0.15)
				)
			)
		)
		(property "MPN" "GRM155C61E475ME15J"
			(at 0 0 180)
			(unlocked yes)
			(layer "F.Fab")
			(hide yes)
			(effects
				(font
					(size 1 1)
					(thickness 0.15)
				)
			)
		)
		(property "Manufacturer" "Murata"
			(at 0 0 180)
			(unlocked yes)
			(layer "F.Fab")
			(hide yes)
			(effects
				(font
					(size 1 1)
					(thickness 0.15)
				)
			)
		)
		(property "License" "Apache-2.0"
			(at 0 0 180)
			(unlocked yes)
			(layer "F.Fab")
			(hide yes)
			(effects
				(font
					(size 1 1)
					(thickness 0.15)
				)
			)
		)
		(property "Author" "Antmicro"
			(at 0 0 180)
			(unlocked yes)
			(layer "F.Fab")
			(hide yes)
			(effects
				(font
					(size 1 1)
					(thickness 0.15)
				)
			)
		)
		(property "Val" "4u7"
			(at 0 0 180)
			(unlocked yes)
			(layer "F.Fab")
			(hide yes)
			(effects
				(font
					(size 1 1)
					(thickness 0.15)
				)
			)
		)
		(property "Voltage" "25V"
			(at 0 0 180)
			(unlocked yes)
			(layer "F.Fab")
			(hide yes)
			(effects
				(font
					(size 1 1)
					(thickness 0.15)
				)
			)
		)
		(property "Dielectric" "X5S"
			(at 0 0 180)
			(unlocked yes)
			(layer "F.Fab")
			(hide yes)
			(effects
				(font
					(size 1 1)
					(thickness 0.15)
				)
			)
		)
		(sheetname "/DCDC/")
		(sheetfile "dcdc.kicad_sch")
		(attr smd)
		(fp_poly
			(pts
				(xy -0.925 -0.47) (xy -0.925 0.47) (xy 0.925 0.47) (xy 0.925 -0.47)
			)
			(stroke
				(width 0.05)
				(type default)
			)
			(fill no)
			(layer "F.CrtYd")
		)
		(fp_line
			(start 0.504 0.248)
			(end -0.494 0.248)
			(stroke
				(width 0.15)
				(type solid)
			)
			(layer "F.Fab")
		)
		(fp_line
			(start 0.504 -0.25)
			(end 0.504 0.248)
			(stroke
				(width 0.15)
				(type solid)
			)
			(layer "F.Fab")
		)
		(fp_line
			(start -0.494 0.248)
			(end -0.494 -0.25)
			(stroke
				(width 0.15)
				(type solid)
			)
			(layer "F.Fab")
		)
		(fp_line
			(start -0.494 -0.25)
			(end 0.504 -0.25)
			(stroke
				(width 0.15)
				(type solid)
			)
			(layer "F.Fab")
		)
		(fp_text user "${REFERENCE}"
			(at -0.939 4.599 0)
			(layer "F.Fab")
			(effects
				(font
					(size 0.7 0.7)
					(thickness 0.15)
				)
				(justify right top)
			)
		)
		(fp_text user "License: Apache-2.0"
			(at -0.939 5.799 0)
			(layer "F.Fab")
			(effects
				(font
					(size 0.7 0.7)
					(thickness 0.15)
				)
				(justify right top)
			)
		)
		(fp_text user "Author: Antmicro"
			(at -0.939 3.399 0)
			(layer "F.Fab")
			(effects
				(font
					(size 0.7 0.7)
					(thickness 0.15)
				)
				(justify right top)
			)
		)
		(pad "1" smd roundrect
			(at -0.48 0 180)
			(size 0.59 0.64)
			(layers "F.Cu" "F.Mask" "F.Paste")
			(roundrect_rratio 0.25)
			(net 1 "GND")
			(pintype "passive")
		)
		(pad "2" smd roundrect
			(at 0.48 0 180)
			(size 0.59 0.64)
			(layers "F.Cu" "F.Mask" "F.Paste")
			(roundrect_rratio 0.25)
			(net 1275 "/DCDC/5V_{AON}_VDRV")
			(pintype "passive")
		)
	)
	(footprint "antmicro-footprints:R_0402_1005Metric"
		(layer "F.Cu")
		(at 132.465349 62.97 180)
		(descr "Resistor SMD 0402")
		(tags "resistor SMD 0402")
		(property "Reference" "R311"
			(at -0.844651 -1.31 0)
			(layer "F.SilkS")
			(effects
				(font
					(size 0.7 0.7)
					(thickness 0.15)
				)
				(justify left bottom)
			)
		)
		(property "Value" "R_100k_0402"
			(at -1.011843 1.772046 0)
			(layer "F.Fab")
			(effects
				(font
					(size 0.7 0.7)
					(thickness 0.15)
				)
				(justify right top)
			)
		)
		(property "Datasheet" "https://www.bourns.com/docs/product-datasheets/cr.pdf"
			(at 0 0 0)
			(layer "F.Fab")
			(hide yes)
			(effects
				(font
					(size 1.27 1.27)
					(thickness 0.15)
				)
			)
		)
		(property "Description" "SMD Chip Resistor, 100 kohm, ± 1%, 62.5 mW, 0402 [1005 Metric], Thick Film, General Purpose"
			(at 0 0 0)
			(layer "F.Fab")
			(hide yes)
			(effects
				(font
					(size 1.27 1.27)
					(thickness 0.15)
				)
			)
		)
		(property "MPN" "CR0402-FX-1003GLF"
			(at 0 0 180)
			(unlocked yes)
			(layer "F.Fab")
			(hide yes)
			(effects
				(font
					(size 1 1)
					(thickness 0.15)
				)
			)
		)
		(property "Manufacturer" "Bourns"
			(at 0 0 180)
			(unlocked yes)
			(layer "F.Fab")
			(hide yes)
			(effects
				(font
					(size 1 1)
					(thickness 0.15)
				)
			)
		)
		(property "License" "Apache-2.0"
			(at 0 0 180)
			(unlocked yes)
			(layer "F.Fab")
			(hide yes)
			(effects
				(font
					(size 1 1)
					(thickness 0.15)
				)
			)
		)
		(property "Author" "Antmicro"
			(at 0 0 180)
			(unlocked yes)
			(layer "F.Fab")
			(hide yes)
			(effects
				(font
					(size 1 1)
					(thickness 0.15)
				)
			)
		)
		(property "Val" "100k"
			(at 0 0 180)
			(unlocked yes)
			(layer "F.Fab")
			(hide yes)
			(effects
				(font
					(size 1 1)
					(thickness 0.15)
				)
			)
		)
		(property "Tolerance" "1%"
			(at 0 0 180)
			(unlocked yes)
			(layer "F.Fab")
			(hide yes)
			(effects
				(font
					(size 1 1)
					(thickness 0.15)
				)
			)
		)
		(sheetname "/DCDC/")
		(sheetfile "dcdc.kicad_sch")
		(attr smd)
		(fp_poly
			(pts
				(xy -0.925 -0.47) (xy 0.925 -0.47) (xy 0.925 0.47) (xy -0.925 0.47)
			)
			(stroke
				(width 0.05)
				(type default)
			)
			(fill no)
			(layer "F.CrtYd")
		)
		(fp_poly
			(pts
				(xy -0.5 -0.25) (xy 0.5 -0.25) (xy 0.5 0.25) (xy -0.5 0.25)
			)
			(stroke
				(width 0.15)
				(type solid)
			)
			(fill no)
			(layer "F.Fab")
		)
		(fp_text user "Author: Antmicro"
			(at -0.95 4.169 0)
			(layer "F.Fab")
			(effects
				(font
					(size 0.7 0.7)
					(thickness 0.15)
				)
				(justify right top)
			)
		)
		(fp_text user "${REFERENCE}"
			(at -0.95 3.168 0)
			(layer "F.Fab")
			(effects
				(font
					(size 0.7 0.7)
					(thickness 0.15)
				)
				(justify right top)
			)
		)
		(fp_text user "License: Apache-2.0"
			(at -0.949999 5.169 0)
			(layer "F.Fab")
			(effects
				(font
					(size 0.7 0.7)
					(thickness 0.15)
				)
				(justify right top)
			)
		)
		(pad "1" smd roundrect
			(at -0.48 0 180)
			(size 0.59 0.64)
			(layers "F.Cu" "F.Mask" "F.Paste")
			(roundrect_rratio 0.25)
			(net 1 "GND")
			(pintype "passive")
		)
		(pad "2" smd roundrect
			(at 0.48 0 180)
			(size 0.59 0.64)
			(layers "F.Cu" "F.Mask" "F.Paste")
			(roundrect_rratio 0.25)
			(net 1307 "/DCDC/5V_{AON}_MODE2")
			(pintype "passive")
		)
	)
	(footprint "antmicro-footprints:LED_0603_1608Metric_G"
		(layer "F.Cu")
		(at 182 55.32 -90)
		(descr "LED SMD 0603 Green")
		(tags "LED SMD 0603 Green")
		(property "Reference" "D6"
			(at -0.28 1.47 90)
			(layer "F.SilkS")
			(effects
				(font
					(size 0.7 0.7)
					(thickness 0.15)
				)
				(justify right top)
			)
		)
		(property "Value" "LED_G_0603_LTST-C190GKT"
			(at -0.001 1.599 90)
			(layer "F.Fab")
			(effects
				(font
					(size 0.7 0.7)
					(thickness 0.15)
				)
				(justify right top)
			)
		)
		(property "Datasheet" "https://media.digikey.com/pdf/Data%20Sheets/Lite-On%20PDFs/LTST-C190GKT.pdf"
			(at 0 0 90)
			(layer "F.Fab")
			(hide yes)
			(effects
				(font
					(size 1.27 1.27)
					(thickness 0.15)
				)
			)
		)
		(property "Description" "LED, Green, SMD, 0603, 20 mA, 2.1 V, 569 nm"
			(at 0 0 90)
			(layer "F.Fab")
			(hide yes)
			(effects
				(font
					(size 1.27 1.27)
					(thickness 0.15)
				)
			)
		)
		(property "MPN" "LTST-C190GKT"
			(at 0 0 270)
			(unlocked yes)
			(layer "F.Fab")
			(hide yes)
			(effects
				(font
					(size 1 1)
					(thickness 0.15)
				)
			)
		)
		(property "Manufacturer" "Lite-On"
			(at 0 0 270)
			(unlocked yes)
			(layer "F.Fab")
			(hide yes)
			(effects
				(font
					(size 1 1)
					(thickness 0.15)
				)
			)
		)
		(property "Author" "Antmicro"
			(at 0 0 270)
			(unlocked yes)
			(layer "F.Fab")
			(hide yes)
			(effects
				(font
					(size 1 1)
					(thickness 0.15)
				)
			)
		)
		(property "License" "Apache-2.0"
			(at 0 0 270)
			(unlocked yes)
			(layer "F.Fab")
			(hide yes)
			(effects
				(font
					(size 1 1)
					(thickness 0.15)
				)
			)
		)
		(property "Color" "Green"
			(at 0 0 270)
			(unlocked yes)
			(layer "F.Fab")
			(hide yes)
			(effects
				(font
					(size 1 1)
					(thickness 0.15)
				)
			)
		)
		(sheetname "/Power/")
		(sheetfile "power.kicad_sch")
		(attr smd)
		(fp_line
			(start 0.22 0.35)
			(end -0.22 0.35)
			(stroke
				(width 0.15)
				(type solid)
			)
			(layer "F.SilkS")
		)
		(fp_line
			(start -0.094672 0.201008)
			(end -0.094672 -0.198992)
			(stroke
				(width 0.1)
				(type solid)
			)
			(layer "F.SilkS")
		)
		(fp_line
			(start 0.105328 0.201008)
			(end -0.094672 0.001008)
			(stroke
				(width 0.1)
				(type solid)
			)
			(layer "F.SilkS")
		)
		(fp_line
			(start 0.105328 0.201008)
			(end 0.105328 -0.198992)
			(stroke
				(width 0.1)
				(type solid)
			)
			(layer "F.SilkS")
		)
		(fp_line
			(start -0.094672 0.001008)
			(end -0.24 0.001008)
			(stroke
				(width 0.1)
				(type solid)
			)
			(layer "F.SilkS")
		)
		(fp_line
			(start -0.094672 0.001008)
			(end 0.105328 -0.198992)
			(stroke
				(width 0.1)
				(type solid)
			)
			(layer "F.SilkS")
		)
		(fp_line
			(start 0.105328 0.001008)
			(end 0.24 0.001)
			(stroke
				(width 0.1)
				(type solid)
			)
			(layer "F.SilkS")
		)
		(fp_line
			(start -1.18 -0.319)
			(end -1.18 0.321)
			(stroke
				(width 0.15)
				(type solid)
			)
			(layer "F.SilkS")
		)
		(fp_line
			(start 0.22 -0.35)
			(end -0.22 -0.35)
			(stroke
				(width 0.15)
				(type solid)
			)
			(layer "F.SilkS")
		)
		(fp_rect
			(start 1.25 0.65)
			(end -1.25 -0.65)
			(stroke
				(width 0.05)
				(type solid)
			)
			(fill no)
			(layer "F.CrtYd")
		)
		(fp_line
			(start -0.199 0.2)
			(end -0.199 0.1)
			(stroke
				(width 0.15)
				(type solid)
			)
			(layer "F.Fab")
		)
		(fp_line
			(start 0.201 0.2)
			(end 0.201 0)
			(stroke
				(width 0.15)
				(type solid)
			)
			(layer "F.Fab")
		)
		(fp_line
			(start -0.199 0)
			(end -0.597 0)
			(stroke
				(width 0.15)
				(type solid)
			)
			(layer "F.Fab")
		)
		(fp_line
			(start -0.101 0)
			(end 0.201 0.2)
			(stroke
				(width 0.15)
				(type solid)
			)
			(layer "F.Fab")
		)
		(fp_line
			(start 0.201 0)
			(end 0.201 -0.202)
			(stroke
				(width 0.15)
				(type solid)
			)
			(layer "F.Fab")
		)
		(fp_line
			(start 0.599 0)
			(end 0.201 0)
			(stroke
				(width 0.15)
				(type solid)
			)
			(layer "F.Fab")
		)
		(fp_line
			(start -0.199 -0.202)
			(end -0.199 0.1)
			(stroke
				(width 0.15)
				(type solid)
			)
			(layer "F.Fab")
		)
		(fp_line
			(start 0.201 -0.202)
			(end -0.101 0)
			(stroke
				(width 0.15)
				(type solid)
			)
			(layer "F.Fab")
		)
		(fp_rect
			(start 0.848 0.4)
			(end -0.85 -0.402)
			(stroke
				(width 0.15)
				(type solid)
			)
			(fill no)
			(layer "F.Fab")
		)
		(fp_text user "${REFERENCE}"
			(at -1.4224 5.999 90)
			(layer "F.Fab")
			(effects
				(font
					(size 0.7 0.7)
					(thickness 0.15)
				)
				(justify right top)
			)
		)
		(fp_text user "License: Apache-2.0"
			(at -1.4224 3.599 90)
			(layer "F.Fab")
			(effects
				(font
					(size 0.7 0.7)
					(thickness 0.15)
				)
				(justify right top)
			)
		)
		(fp_text user "Author: Antmicro"
			(at -1.4224 4.799 90)
			(layer "F.Fab")
			(effects
				(font
					(size 0.7 0.7)
					(thickness 0.15)
				)
				(justify right top)
			)
		)
		(pad "1" smd roundrect
			(at -0.7 0 90)
			(size 0.8 1)
			(layers "F.Cu" "F.Mask" "F.Paste")
			(roundrect_rratio 0.2)
			(net 1 "GND")
			(pinfunction "C")
			(pintype "passive")
		)
		(pad "2" smd roundrect
			(at 0.7 0 90)
			(size 0.8 1)
			(layers "F.Cu" "F.Mask" "F.Paste")
			(roundrect_rratio 0.2)
			(net 1108 "Net-(D6-A)")
			(pinfunction "A")
			(pintype "passive")
		)
	)
	(footprint "antmicro-footprints:C_0402_1005Metric"
		(layer "F.Cu")
		(at 206.75 88.470856 180)
		(descr "Capacitor SMD 0402")
		(tags "capacitor SMD 0402")
		(property "Reference" "C316"
			(at -0.95 -0.429144 180)
			(layer "F.SilkS")
			(effects
				(font
					(size 0.7 0.7)
					(thickness 0.15)
				)
				(justify left bottom)
			)
		)
		(property "Value" "C_100n_0402"
			(at -1.022927 2.155213 180)
			(layer "F.Fab")
			(effects
				(font
					(size 0.7 0.7)
					(thickness 0.15)
				)
				(justify left bottom)
			)
		)
		(property "Datasheet" "https://www.murata.com/products/productdetail?partno=GRM155R61H104KE14%23"
			(at 0 0 180)
			(layer "F.Fab")
			(hide yes)
			(effects
				(font
					(size 1.27 1.27)
					(thickness 0.15)
				)
			)
		)
		(property "Description" "SMD Multilayer Ceramic Capacitor, 0.1 µF, 50 V, 0402 [1005 Metric], ± 10%, X5R, GRM Series"
			(at 0 0 180)
			(layer "F.Fab")
			(hide yes)
			(effects
				(font
					(size 1.27 1.27)
					(thickness 0.15)
				)
			)
		)
		(property "Manufacturer" "Murata"
			(at 0 0 180)
			(unlocked yes)
			(layer "F.Fab")
			(hide yes)
			(effects
				(font
					(size 1 1)
					(thickness 0.15)
				)
			)
		)
		(property "MPN" "GRM155R61H104KE14D"
			(at 0 0 180)
			(unlocked yes)
			(layer "F.Fab")
			(hide yes)
			(effects
				(font
					(size 1 1)
					(thickness 0.15)
				)
			)
		)
		(property "Val" "100n"
			(at 0 0 180)
			(unlocked yes)
			(layer "F.Fab")
			(hide yes)
			(effects
				(font
					(size 1 1)
					(thickness 0.15)
				)
			)
		)
		(property "License" "Apache-2.0"
			(at 0 0 180)
			(unlocked yes)
			(layer "F.Fab")
			(hide yes)
			(effects
				(font
					(size 1 1)
					(thickness 0.15)
				)
			)
		)
		(property "Author" "Antmicro"
			(at 0 0 180)
			(unlocked yes)
			(layer "F.Fab")
			(hide yes)
			(effects
				(font
					(size 1 1)
					(thickness 0.15)
				)
			)
		)
		(property "Voltage" "50V"
			(at 0 0 180)
			(unlocked yes)
			(layer "F.Fab")
			(hide yes)
			(effects
				(font
					(size 1 1)
					(thickness 0.15)
				)
			)
		)
		(property "Dielectric" "X5R"
			(at 0 0 180)
			(unlocked yes)
			(layer "F.Fab")
			(hide yes)
			(effects
				(font
					(size 1 1)
					(thickness 0.15)
				)
			)
		)
		(sheetname "/SoM_IO2/")
		(sheetfile "som_io2.kicad_sch")
		(attr smd)
		(fp_rect
			(start -0.925 -0.47)
			(end 0.925 0.47)
			(stroke
				(width 0.05)
				(type default)
			)
			(fill no)
			(layer "F.CrtYd")
		)
		(fp_line
			(start 0.504 0.248)
			(end -0.494 0.248)
			(stroke
				(width 0.15)
				(type solid)
			)
			(layer "F.Fab")
		)
		(fp_line
			(start 0.504 -0.25)
			(end 0.504 0.248)
			(stroke
				(width 0.15)
				(type solid)
			)
			(layer "F.Fab")
		)
		(fp_line
			(start -0.494 0.248)
			(end -0.494 -0.25)
			(stroke
				(width 0.15)
				(type solid)
			)
			(layer "F.Fab")
		)
		(fp_line
			(start -0.494 -0.25)
			(end 0.504 -0.25)
			(stroke
				(width 0.15)
				(type solid)
			)
			(layer "F.Fab")
		)
		(fp_text user "${REFERENCE}"
			(at -0.939 4.599 180)
			(layer "F.Fab")
			(effects
				(font
					(size 0.7 0.7)
					(thickness 0.15)
				)
				(justify left bottom)
			)
		)
		(fp_text user "License: Apache-2.0"
			(at -0.939 5.799 180)
			(layer "F.Fab")
			(effects
				(font
					(size 0.7 0.7)
					(thickness 0.15)
				)
				(justify left bottom)
			)
		)
		(fp_text user "Author: Antmicro"
			(at -0.939 3.399 180)
			(layer "F.Fab")
			(effects
				(font
					(size 0.7 0.7)
					(thickness 0.15)
				)
				(justify left bottom)
			)
		)
		(pad "1" smd roundrect
			(at -0.48 0 180)
			(size 0.59 0.64)
			(layers "F.Cu" "F.Mask" "F.Paste")
			(roundrect_rratio 0.25)
			(net 612 "/SoM_IO2/DP0.TX1+")
			(pintype "passive")
		)
		(pad "2" smd roundrect
			(at 0.48 0 180)
			(size 0.59 0.64)
			(layers "F.Cu" "F.Mask" "F.Paste")
			(roundrect_rratio 0.25)
			(net 596 "/SoM_IO2/DP0.TX1_C+")
			(pintype "passive")
		)
	)
)
